# S9S_MB_2U (Grand Teton) — schematic netlist excerpt (pin names and nets, part order shuffled) for the footprints in the layout excerpt that follows; sources: Cadence DE-HDL packaged netlist, KiCad conversion of 03242023_DA0F0TMBIJ0_F0T_Motherboard_J_brd_V01_OCP.brd

J42  SCONN60_ASP21410801  SCONN60_ASP-214108-01 IO  pkg CON_60S2H2D4S_P0-5_LDV  page 131
  \1\  = P1V05_PCH_AUX
  \2\  = JTAG_DBP_TMS_R
  \3\  = JTAG_DBP_CPU_GTL_TCK_R
  \4\  = JTAG_DBP_TDO_R
  \5\  = JTAG_DBP_TDI_R
  \6\  = JTAG_RST_DBP_RST_CO_N
  \7\  = JTAG_DBP_PMODE
  \8\  = PD_TRST_P3
  \9\  = NC_MIPI60_P9
  \10\  = JTAG_DBP_PREQ_N_R
  \11\  = JTAG_DBP_PRDY_R1_N
  \12\  = P1V8_PCH_AUX
  \13\  = JTAG_TRC_PCH_PTI0_CLK
  \14\  = GND
  \15\  = JTAG_DBP_PCH_DEBUG_CONSENT_N
  \16\  = GND
  \17\  = JTAG_DBP_PRESENT_R_N
  \18\  = NC_DBP_P18
  \19\  = JTAG_TRC_PCH_PTI<0>
  \20\  = NC_DBP_P20
  \21\  = JTAG_TRC_PCH_PTI<1>
  \22\  = NC_DBP_P22
  \23\  = JTAG_TRC_PCH_PTI<2>
  \24\  = NC_DBP_P24
  \25\  = JTAG_TRC_PCH_PTI<3>
  \26\  = NC_DBP_P26
  \27\  = JTAG_TRC_PCH_PTI<4>
  \28\  = NC_DBP_P28
  \29\  = JTAG_TRC_PCH_PTI<5>
  \30\  = NC_DBP_P30
  \31\  = JTAG_TRC_PCH_PTI<6>
  \32\  = NC_DBP_P32
  \33\  = JTAG_TRC_PCH_PTI<7>
  \34\  = NC_DBP_P34
  \35\  = JTAG_TRC_PCH_PTI<8>
  \36\  = JTAG_DBP_BOOT_HALT_N
  \37\  = JTAG_TRC_PCH_PTI<9>
  \38\  = FM_CPU_FBRK_DEBUG_N
  \39\  = JTAG_TRC_PCH_PTI<10>
  \40\  = JTAG_DBP_POWER_BTN_N
  \41\  = JTAG_TRC_PCH_PTI<11>
  \42\  = JTAG_RST_DBP_RSMRST_N
  \43\  = JTAG_TRC_PCH_PTI<12>
  \44\  = NC_DBP_P44
  \45\  = JTAG_TRC_PCH_PTI<13>
  \46\  = NC_DBP_P46
  \47\  = JTAG_TRC_PCH_PTI<14>
  \48\  = SMB_HOST_3V3AUX_XDP_R_SCL
  \49\  = JTAG_TRC_PCH_PTI<15>
  \50\  = SMB_HOST_3V3AUX_XDP_R_SDA
  \51\  = JTAG_DBP_TCK_R_TCK
  \52\  = P3V3_AUX
  \53\  = JTAG_DBP_CPU_HOOK9_MBP3_GTL_N
  \54\  = NC_DBP_P54
  \55\  = JTAG_DBP_CPU_HOOK8_MBP2_GTL_N
  \56\  = NC_DBP_P56
  \57\  = GND
  \58\  = GND
  \59\  = JTAG_TRC_PCH_PTI1_CLK
  \60\  = GND
  G1  = GND
  G2  = GND
  G3  = GND
  G4  = GND

(kicad_pcb
	(version 20260206)
	(generator "pcbnew")
	(generator_version "10.0")
	(general
		(thickness 1.6)
		(legacy_teardrops no)
	)
	(paper "A4")
	(title_block
		(title "03242023_DA0F0TMBIJ0_F0T_Motherboard_J_brd_V01_OCP.brd")
		(comment 1 "Grand Teton / footprint 3716 of 6105 (J42), pads 1-44 of 66")
	)
	(layers
		(0 "F.Cu" signal "TOP")
		(4 "In1.Cu" signal "GND")
		(6 "In2.Cu" signal "IN1")
		(8 "In3.Cu" signal "GND1")
		(10 "In4.Cu" signal "IN2")
		(12 "In5.Cu" signal "GND2")
		(14 "In6.Cu" signal "IN3")
		(16 "In7.Cu" signal "GND3")
		(18 "In8.Cu" signal "VCC")
		(20 "In9.Cu" signal "VCC1")
		(22 "In10.Cu" signal "GND4")
		(24 "In11.Cu" signal "IN4")
		(26 "In12.Cu" signal "GND5")
		(28 "In13.Cu" signal "IN5")
		(30 "In14.Cu" signal "GND6")
		(32 "In15.Cu" signal "IN6")
		(34 "In16.Cu" signal "GND7")
		(2 "B.Cu" signal "BOTTOM")
		(9 "F.Adhes" user "F.Adhesive")
		(11 "B.Adhes" user "B.Adhesive")
		(13 "F.Paste" user "Package Geometry/Pastemask Top")
		(15 "B.Paste" user "Package Geometry/Pastemask Bottom")
		(5 "F.SilkS" user "Ref Des/Silkscreen Top")
		(7 "B.SilkS" user "Ref Des/Silkscreen Bottom")
		(1 "F.Mask" user "Board Geometry/Soldermask Top")
		(3 "B.Mask" user "Board Geometry/Soldermask Bottom")
		(17 "Dwgs.User" user "User.Drawings")
		(19 "Cmts.User" user "User.Comments")
		(21 "Eco1.User" user "User.Eco1")
		(23 "Eco2.User" user "User.Eco2")
		(25 "Edge.Cuts" user "Board Geometry/Outline")
		(27 "Margin" user)
		(31 "F.CrtYd" user "Package Geometry/Place Bound Top")
		(29 "B.CrtYd" user "Package Geometry/Place Bound Bottom")
		(35 "F.Fab" user "Ref Des/Assembly Top")
		(33 "B.Fab" user "Ref Des/Assembly Bottom")
	)
	(footprint ""
		(layer "F.Cu")
		(at 394.899896 -56.999886)
		(property "Reference" "J42"
			(at 4.46278 8.605012 0)
			(unlocked yes)
			(layer "F.SilkS")
			(effects
				(font
					(size 0.7874 0.5842)
					(thickness 0.1524)
				)
				(justify left)
			)
		)
		(property "Value" ""
			(at 0 0 0)
			(layer "F.Fab")
			(effects
				(font
					(size 1.27 1.27)
				)
			)
		)
		(duplicate_pad_numbers_are_jumpers no)
		(pad "" np_thru_hole circle
			(at 2.670048 -10.065004 270)
			(size 1.0414 1.0414)
			(drill 1.0414)
			(layers "*.Cu" "*.Mask")
			(clearance 0.381)
			(thermal_gap 0.381)
		)
		(pad "" np_thru_hole circle
			(at 2.670048 10.065004 270)
			(size 1.0414 1.0414)
			(drill 1.0414)
			(layers "*.Cu" "*.Mask")
			(clearance 0.381)
			(thermal_gap 0.381)
		)
		(pad "1" smd rect
			(at -2.86512 -7.249922 270)
			(size 0.2794 2.286)
			(layers "F.Cu" "F.Mask" "F.Paste")
			(net "P1V05_PCH_AUX")
		)
		(pad "2" smd rect
			(at 2.86512 -7.249922 270)
			(size 0.2794 2.286)
			(layers "F.Cu" "F.Mask" "F.Paste")
			(net "JTAG_DBP_TMS_R")
		)
		(pad "3" smd rect
			(at -2.86512 -6.75005 270)
			(size 0.2794 2.286)
			(layers "F.Cu" "F.Mask" "F.Paste")
			(net "JTAG_DBP_CPU_GTL_TCK_R")
		)
		(pad "4" smd rect
			(at 2.86512 -6.75005 270)
			(size 0.2794 2.286)
			(layers "F.Cu" "F.Mask" "F.Paste")
			(net "JTAG_DBP_TDO_R")
		)
		(pad "5" smd rect
			(at -2.86512 -6.249924 270)
			(size 0.2794 2.286)
			(layers "F.Cu" "F.Mask" "F.Paste")
			(net "JTAG_DBP_TDI_R")
		)
		(pad "6" smd rect
			(at 2.86512 -6.249924 270)
			(size 0.2794 2.286)
			(layers "F.Cu" "F.Mask" "F.Paste")
			(net "JTAG_RST_DBP_RST_CO_N")
		)
		(pad "7" smd rect
			(at -2.86512 -5.750052 270)
			(size 0.2794 2.286)
			(layers "F.Cu" "F.Mask" "F.Paste")
			(net "JTAG_DBP_PMODE")
		)
		(pad "8" smd rect
			(at 2.86512 -5.750052 270)
			(size 0.2794 2.286)
			(layers "F.Cu" "F.Mask" "F.Paste")
			(net "PD_TRST_P3")
		)
		(pad "9" smd rect
			(at -2.86512 -5.249926 270)
			(size 0.2794 2.286)
			(layers "F.Cu" "F.Mask" "F.Paste")
			(net "NC_MIPI60_P9")
		)
		(pad "10" smd rect
			(at 2.86512 -5.249926 270)
			(size 0.2794 2.286)
			(layers "F.Cu" "F.Mask" "F.Paste")
			(net "JTAG_DBP_PREQ_N_R")
		)
		(pad "11" smd rect
			(at -2.86512 -4.750054 270)
			(size 0.2794 2.286)
			(layers "F.Cu" "F.Mask" "F.Paste")
			(net "JTAG_DBP_PRDY_R1_N")
		)
		(pad "12" smd rect
			(at 2.86512 -4.750054 270)
			(size 0.2794 2.286)
			(layers "F.Cu" "F.Mask" "F.Paste")
			(net "P1V8_PCH_AUX")
		)
		(pad "13" smd rect
			(at -2.86512 -4.249928 270)
			(size 0.2794 2.286)
			(layers "F.Cu" "F.Mask" "F.Paste")
			(net "JTAG_TRC_PCH_PTI0_CLK")
		)
		(pad "14" smd rect
			(at 2.86512 -4.249928 270)
			(size 0.2794 2.286)
			(layers "F.Cu" "F.Mask" "F.Paste")
			(net "GND")
		)
		(pad "15" smd rect
			(at -2.86512 -3.750056 270)
			(size 0.2794 2.286)
			(layers "F.Cu" "F.Mask" "F.Paste")
			(net "JTAG_DBP_PCH_DEBUG_CONSENT_N")
		)
		(pad "16" smd rect
			(at 2.86512 -3.750056 270)
			(size 0.2794 2.286)
			(layers "F.Cu" "F.Mask" "F.Paste")
			(net "GND")
		)
		(pad "17" smd rect
			(at -2.86512 -3.24993 270)
			(size 0.2794 2.286)
			(layers "F.Cu" "F.Mask" "F.Paste")
			(net "JTAG_DBP_PRESENT_R_N")
		)
		(pad "18" smd rect
			(at 2.86512 -3.24993 270)
			(size 0.2794 2.286)
			(layers "F.Cu" "F.Mask" "F.Paste")
			(net "NC_DBP_P18")
		)
		(pad "19" smd rect
			(at -2.86512 -2.750058 270)
			(size 0.2794 2.286)
			(layers "F.Cu" "F.Mask" "F.Paste")
			(net "JTAG_TRC_PCH_PTI<0>")
		)
		(pad "20" smd rect
			(at 2.86512 -2.750058 270)
			(size 0.2794 2.286)
			(layers "F.Cu" "F.Mask" "F.Paste")
			(net "NC_DBP_P20")
		)
		(pad "21" smd rect
			(at -2.86512 -2.249932 270)
			(size 0.2794 2.286)
			(layers "F.Cu" "F.Mask" "F.Paste")
			(net "JTAG_TRC_PCH_PTI<1>")
		)
		(pad "22" smd rect
			(at 2.86512 -2.249932 270)
			(size 0.2794 2.286)
			(layers "F.Cu" "F.Mask" "F.Paste")
			(net "NC_DBP_P22")
		)
		(pad "23" smd rect
			(at -2.86512 -1.75006 270)
			(size 0.2794 2.286)
			(layers "F.Cu" "F.Mask" "F.Paste")
			(net "JTAG_TRC_PCH_PTI<2>")
		)
		(pad "24" smd rect
			(at 2.86512 -1.75006 270)
			(size 0.2794 2.286)
			(layers "F.Cu" "F.Mask" "F.Paste")
			(net "NC_DBP_P24")
		)
		(pad "25" smd rect
			(at -2.86512 -1.249934 270)
			(size 0.2794 2.286)
			(layers "F.Cu" "F.Mask" "F.Paste")
			(net "JTAG_TRC_PCH_PTI<3>")
		)
		(pad "26" smd rect
			(at 2.86512 -1.249934 270)
			(size 0.2794 2.286)
			(layers "F.Cu" "F.Mask" "F.Paste")
			(net "NC_DBP_P26")
		)
		(pad "27" smd rect
			(at -2.86512 -0.750062 270)
			(size 0.2794 2.286)
			(layers "F.Cu" "F.Mask" "F.Paste")
			(net "JTAG_TRC_PCH_PTI<4>")
		)
		(pad "28" smd rect
			(at 2.86512 -0.750062 270)
			(size 0.2794 2.286)
			(layers "F.Cu" "F.Mask" "F.Paste")
			(net "NC_DBP_P28")
		)
		(pad "29" smd rect
			(at -2.86512 -0.249936 270)
			(size 0.2794 2.286)
			(layers "F.Cu" "F.Mask" "F.Paste")
			(net "JTAG_TRC_PCH_PTI<5>")
		)
		(pad "30" smd rect
			(at 2.86512 -0.249936 270)
			(size 0.2794 2.286)
			(layers "F.Cu" "F.Mask" "F.Paste")
			(net "NC_DBP_P30")
		)
		(pad "31" smd rect
			(at -2.86512 0.249936 270)
			(size 0.2794 2.286)
			(layers "F.Cu" "F.Mask" "F.Paste")
			(net "JTAG_TRC_PCH_PTI<6>")
		)
		(pad "32" smd rect
			(at 2.86512 0.249936 270)
			(size 0.2794 2.286)
			(layers "F.Cu" "F.Mask" "F.Paste")
			(net "NC_DBP_P32")
		)
		(pad "33" smd rect
			(at -2.86512 0.750062 270)
			(size 0.2794 2.286)
			(layers "F.Cu" "F.Mask" "F.Paste")
			(net "JTAG_TRC_PCH_PTI<7>")
		)
		(pad "34" smd rect
			(at 2.86512 0.750062 270)
			(size 0.2794 2.286)
			(layers "F.Cu" "F.Mask" "F.Paste")
			(net "NC_DBP_P34")
		)
		(pad "35" smd rect
			(at -2.86512 1.249934 270)
			(size 0.2794 2.286)
			(layers "F.Cu" "F.Mask" "F.Paste")
			(net "JTAG_TRC_PCH_PTI<8>")
		)
		(pad "36" smd rect
			(at 2.86512 1.249934 270)
			(size 0.2794 2.286)
			(layers "F.Cu" "F.Mask" "F.Paste")
			(net "JTAG_DBP_BOOT_HALT_N")
		)
		(pad "37" smd rect
			(at -2.86512 1.75006 270)
			(size 0.2794 2.286)
			(layers "F.Cu" "F.Mask" "F.Paste")
			(net "JTAG_TRC_PCH_PTI<9>")
		)
		(pad "38" smd rect
			(at 2.86512 1.75006 270)
			(size 0.2794 2.286)
			(layers "F.Cu" "F.Mask" "F.Paste")
			(net "FM_CPU_FBRK_DEBUG_N")
		)
		(pad "39" smd rect
			(at -2.86512 2.249932 270)
			(size 0.2794 2.286)
			(layers "F.Cu" "F.Mask" "F.Paste")
			(net "JTAG_TRC_PCH_PTI<10>")
		)
		(pad "40" smd rect
			(at 2.86512 2.249932 270)
			(size 0.2794 2.286)
			(layers "F.Cu" "F.Mask" "F.Paste")
			(net "JTAG_DBP_POWER_BTN_N")
		)
		(pad "41" smd rect
			(at -2.86512 2.750058 270)
			(size 0.2794 2.286)
			(layers "F.Cu" "F.Mask" "F.Paste")
			(net "JTAG_TRC_PCH_PTI<11>")
		)
		(pad "42" smd rect
			(at 2.86512 2.750058 270)
			(size 0.2794 2.286)
			(layers "F.Cu" "F.Mask" "F.Paste")
			(net "JTAG_RST_DBP_RSMRST_N")
		)
	)
)
